(kicad_pcb
	(version 20241229)
	(generator "pcbnew")
	(generator_version "9.0")
	(general
		(thickness 1.6642)
		(legacy_teardrops no)
	)
	(paper "A3")
	(title_block
		(title "PolarFire SoM")
		(date "2025-07-22")
		(rev "1.1.4")
		(company "Antmicro Ltd")
		(comment 1 "www.antmicro.com")
		(comment 9 "footprints 334-338 of 470")
	)
	(layers
		(0 "F.Cu" mixed)
		(4 "In1.Cu" power)
		(6 "In2.Cu" signal)
		(8 "In3.Cu" power)
		(10 "In4.Cu" signal)
		(12 "In5.Cu" power)
		(14 "In6.Cu" power)
		(16 "In7.Cu" signal)
		(18 "In8.Cu" power)
		(20 "In9.Cu" signal)
		(22 "In10.Cu" power)
		(24 "In11.Cu" signal)
		(26 "In12.Cu" signal)
		(2 "B.Cu" mixed)
		(9 "F.Adhes" user "F.Adhesive")
		(11 "B.Adhes" user "B.Adhesive")
		(13 "F.Paste" user)
		(15 "B.Paste" user)
		(5 "F.SilkS" user "F.Silkscreen")
		(7 "B.SilkS" user "B.Silkscreen")
		(1 "F.Mask" user)
		(3 "B.Mask" user)
		(17 "Dwgs.User" user "User.Drawings")
		(19 "Cmts.User" user "User.Comments")
		(21 "Eco1.User" user "User.Eco1")
		(23 "Eco2.User" user "User.Eco2")
		(25 "Edge.Cuts" user)
		(27 "Margin" user)
		(31 "F.CrtYd" user "F.Courtyard")
		(29 "B.CrtYd" user "B.Courtyard")
		(35 "F.Fab" user)
		(33 "B.Fab" user)
	)
	(footprint "antmicro-footprints:C_0603_1608Metric"
		(layer "B.Cu")
		(at 190.78 135.52)
		(descr "Capacitor SMD 0603")
		(tags "capacitor 0603")
		(property "Reference" "C54"
			(at -0.58 -0.72 0)
			(layer "B.SilkS")
			(effects
				(font
					(size 0.7 0.7)
					(thickness 0.15)
				)
				(justify right bottom mirror)
			)
		)
		(property "Value" "C_47u_0603"
			(at -1.42757 -1.770288 0)
			(layer "B.Fab")
			(hide yes)
			(effects
				(font
					(size 0.7 0.7)
					(thickness 0.15)
				)
				(justify right bottom mirror)
			)
		)
		(property "Datasheet" "https://www.murata.com/products/productdetail?partno=GRM188R60J476ME15%23"
			(at 0 0 0)
			(layer "F.Fab")
			(hide yes)
			(effects
				(font
					(size 1.27 1.27)
					(thickness 0.15)
				)
			)
		)
		(property "Description" "SMD Multilayer Ceramic Capacitor, 47 µF, 6.3 V, 0603 [1608 Metric], ± 20%, X5R, GRM Series"
			(at 0 0 0)
			(layer "F.Fab")
			(hide yes)
			(effects
				(font
					(size 1.27 1.27)
					(thickness 0.15)
				)
			)
		)
		(property "Author" "Antmicro"
			(at 0 0 0)
			(layer "B.Fab")
			(hide yes)
			(effects
				(font
					(size 1 1)
					(thickness 0.15)
				)
				(justify mirror)
			)
		)
		(property "Capacitance" "47u"
			(at 0 0 0)
			(layer "B.Fab")
			(hide yes)
			(effects
				(font
					(size 1 1)
					(thickness 0.15)
				)
				(justify mirror)
			)
		)
		(property "Dielectric" "X7R"
			(at 0 0 0)
			(layer "B.Fab")
			(hide yes)
			(effects
				(font
					(size 1 1)
					(thickness 0.15)
				)
				(justify mirror)
			)
		)
		(property "License" "Apache-2.0"
			(at 0 0 0)
			(layer "B.Fab")
			(hide yes)
			(effects
				(font
					(size 1 1)
					(thickness 0.15)
				)
				(justify mirror)
			)
		)
		(property "MPN" "GRM188R60J476ME15D"
			(at 0 0 0)
			(layer "B.Fab")
			(hide yes)
			(effects
				(font
					(size 1 1)
					(thickness 0.15)
				)
				(justify mirror)
			)
		)
		(property "Manufacturer" "Murata"
			(at 0 0 0)
			(layer "B.Fab")
			(hide yes)
			(effects
				(font
					(size 1 1)
					(thickness 0.15)
				)
				(justify mirror)
			)
		)
		(property "Public" ""
			(at 0 0 0)
			(layer "B.Fab")
			(hide yes)
			(effects
				(font
					(size 1 1)
					(thickness 0.15)
				)
				(justify mirror)
			)
		)
		(property "Val" "47u"
			(at 0 0 0)
			(layer "B.Fab")
			(hide yes)
			(effects
				(font
					(size 1 1)
					(thickness 0.15)
				)
				(justify mirror)
			)
		)
		(property "Voltage" "50V"
			(at 0 0 0)
			(layer "B.Fab")
			(hide yes)
			(effects
				(font
					(size 1 1)
					(thickness 0.15)
				)
				(justify mirror)
			)
		)
		(sheetname "/FPGA Supply/")
		(sheetfile "fpga-supply.kicad_sch")
		(attr smd)
		(fp_line
			(start -0.15 -0.4)
			(end 0.15 -0.4)
			(stroke
				(width 0.15)
				(type solid)
			)
			(layer "B.SilkS")
		)
		(fp_line
			(start -0.15 0.4)
			(end 0.15 0.4)
			(stroke
				(width 0.15)
				(type solid)
			)
			(layer "B.SilkS")
		)
		(fp_rect
			(start -1.25 0.65)
			(end 1.25 -0.65)
			(stroke
				(width 0.05)
				(type solid)
			)
			(fill no)
			(layer "B.CrtYd")
		)
		(fp_rect
			(start -0.8 0.4)
			(end 0.8 -0.4)
			(stroke
				(width 0.15)
				(type solid)
			)
			(fill no)
			(layer "B.Fab")
		)
		(fp_text user "${REFERENCE}"
			(at -1.682 -3.895 180)
			(layer "B.Fab")
			(effects
				(font
					(size 0.7 0.7)
					(thickness 0.15)
				)
				(justify left bottom mirror)
			)
		)
		(fp_text user "Author: Antmicro"
			(at -1.682 -4.894 180)
			(layer "B.Fab")
			(effects
				(font
					(size 0.7 0.7)
					(thickness 0.15)
				)
				(justify left bottom mirror)
			)
		)
		(fp_text user "License: Apache-2.0"
			(at -1.682 -5.895 180)
			(layer "B.Fab")
			(effects
				(font
					(size 0.7 0.7)
					(thickness 0.15)
				)
				(justify left bottom mirror)
			)
		)
		(pad "1" smd roundrect
			(at -0.7 0)
			(size 0.8 1)
			(layers "B.Cu" "B.Mask" "B.Paste")
			(roundrect_rratio 0.2)
			(net 417 "GND")
			(pintype "passive")
		)
		(pad "2" smd roundrect
			(at 0.7 0)
			(size 0.8 1)
			(layers "B.Cu" "B.Mask" "B.Paste")
			(roundrect_rratio 0.2)
			(net 48 "+1V8")
			(pintype "passive")
		)
	)
	(footprint "antmicro-footprints:R_0603_1608Metric"
		(layer "B.Cu")
		(at 184.225 139.25)
		(descr "Resistor SMD 0603")
		(tags "resistor SMD 0603")
		(property "Reference" "R47"
			(at 1.6 -0.675 180)
			(layer "B.SilkS")
			(effects
				(font
					(size 0.7 0.7)
					(thickness 0.15)
				)
				(justify left bottom mirror)
			)
		)
		(property "Value" "R_0R01_0603"
			(at 0 -1.6 180)
			(layer "B.Fab")
			(hide yes)
			(effects
				(font
					(size 0.7 0.7)
					(thickness 0.15)
				)
				(justify left bottom mirror)
			)
		)
		(property "Datasheet" "https://www.bourns.com/docs/product-datasheets/cfn-a.pdf"
			(at 0 0 0)
			(layer "F.Fab")
			(hide yes)
			(effects
				(font
					(size 1.27 1.27)
					(thickness 0.15)
				)
			)
		)
		(property "Description" "SMD Chip Resistor, 10 mohm, ± 1%, 0.5 W, 0603 [1608 Metric], Metal Foil, Current Sensing"
			(at 0 0 0)
			(layer "F.Fab")
			(hide yes)
			(effects
				(font
					(size 1.27 1.27)
					(thickness 0.15)
				)
			)
		)
		(property "Author" "Antmicro"
			(at 0 0 0)
			(layer "B.Fab")
			(hide yes)
			(effects
				(font
					(size 1 1)
					(thickness 0.15)
				)
				(justify mirror)
			)
		)
		(property "License" "Apache-2.0"
			(at 0 0 0)
			(layer "B.Fab")
			(hide yes)
			(effects
				(font
					(size 1 1)
					(thickness 0.15)
				)
				(justify mirror)
			)
		)
		(property "MPN" "CFN0603AFZ-R010ELF"
			(at 0 0 0)
			(layer "B.Fab")
			(hide yes)
			(effects
				(font
					(size 1 1)
					(thickness 0.15)
				)
				(justify mirror)
			)
		)
		(property "Manufacturer" "Bourns"
			(at 0 0 0)
			(layer "B.Fab")
			(hide yes)
			(effects
				(font
					(size 1 1)
					(thickness 0.15)
				)
				(justify mirror)
			)
		)
		(property "Public" ""
			(at 0 0 0)
			(layer "B.Fab")
			(hide yes)
			(effects
				(font
					(size 1 1)
					(thickness 0.15)
				)
				(justify mirror)
			)
		)
		(property "Tolerance" "1%"
			(at 0 0 0)
			(layer "B.Fab")
			(hide yes)
			(effects
				(font
					(size 1 1)
					(thickness 0.15)
				)
				(justify mirror)
			)
		)
		(property "Val" "0R01"
			(at 0 0 0)
			(layer "B.Fab")
			(hide yes)
			(effects
				(font
					(size 1 1)
					(thickness 0.15)
				)
				(justify mirror)
			)
		)
		(sheetname "/Supply/")
		(sheetfile "supply.kicad_sch")
		(attr smd)
		(fp_line
			(start -0.15 -0.4)
			(end 0.15 -0.4)
			(stroke
				(width 0.15)
				(type solid)
			)
			(layer "B.SilkS")
		)
		(fp_line
			(start -0.15 0.4)
			(end 0.15 0.4)
			(stroke
				(width 0.15)
				(type solid)
			)
			(layer "B.SilkS")
		)
		(fp_rect
			(start -1.25 0.65)
			(end 1.25 -0.65)
			(stroke
				(width 0.05)
				(type solid)
			)
			(fill no)
			(layer "B.CrtYd")
		)
		(fp_rect
			(start -0.8 0.4)
			(end 0.8 -0.4)
			(stroke
				(width 0.15)
				(type solid)
			)
			(fill no)
			(layer "B.Fab")
		)
		(fp_text user "License: Apache-2.0"
			(at -1.25 -5.9 180)
			(layer "B.Fab")
			(effects
				(font
					(size 0.7 0.7)
					(thickness 0.15)
				)
				(justify left bottom mirror)
			)
		)
		(fp_text user "Author: Antmicro"
			(at -1.25 -4.9 180)
			(layer "B.Fab")
			(effects
				(font
					(size 0.7 0.7)
					(thickness 0.15)
				)
				(justify left bottom mirror)
			)
		)
		(fp_text user "${REFERENCE}"
			(at -1.25 -3.898 180)
			(layer "B.Fab")
			(effects
				(font
					(size 0.7 0.7)
					(thickness 0.15)
				)
				(justify left bottom mirror)
			)
		)
		(pad "1" smd roundrect
			(at -0.7 0)
			(size 0.8 1)
			(layers "B.Cu" "B.Mask" "B.Paste")
			(roundrect_rratio 0.2)
			(net 272 "/Supply/SENSE3_P")
			(pintype "passive")
		)
		(pad "2" smd roundrect
			(at 0.7 0)
			(size 0.8 1)
			(layers "B.Cu" "B.Mask" "B.Paste")
			(roundrect_rratio 0.2)
			(net 2 "+1V1")
			(pintype "passive")
		)
	)
	(footprint "antmicro-footprints:C_0402_1005Metric"
		(layer "B.Cu")
		(at 211.72 119.384)
		(descr "Capacitor SMD 0402")
		(tags "capacitor SMD 0402")
		(property "Reference" "C261"
			(at -1.795 1.416 0)
			(layer "B.SilkS")
			(effects
				(font
					(size 0.7 0.7)
					(thickness 0.15)
				)
				(justify right bottom mirror)
			)
		)
		(property "Value" "C_100n_0402"
			(at -1.022927 -2.155213 0)
			(layer "B.Fab")
			(hide yes)
			(effects
				(font
					(size 0.7 0.7)
					(thickness 0.15)
				)
				(justify right bottom mirror)
			)
		)
		(property "Datasheet" "https://www.murata.com/products/productdetail?partno=GRM155R61H104KE14%23"
			(at 0 0 0)
			(layer "F.Fab")
			(hide yes)
			(effects
				(font
					(size 1.27 1.27)
					(thickness 0.15)
				)
			)
		)
		(property "Description" "SMD Multilayer Ceramic Capacitor, 0.1 µF, 50 V, 0402 [1005 Metric], ± 10%, X5R, GRM Series"
			(at 0 0 0)
			(layer "F.Fab")
			(hide yes)
			(effects
				(font
					(size 1.27 1.27)
					(thickness 0.15)
				)
			)
		)
		(property "Author" "Antmicro"
			(at 0 0 0)
			(layer "B.Fab")
			(hide yes)
			(effects
				(font
					(size 1 1)
					(thickness 0.15)
				)
				(justify mirror)
			)
		)
		(property "Dielectric" "X5R"
			(at 0 0 0)
			(layer "B.Fab")
			(hide yes)
			(effects
				(font
					(size 1 1)
					(thickness 0.15)
				)
				(justify mirror)
			)
		)
		(property "License" "Apache-2.0"
			(at 0 0 0)
			(layer "B.Fab")
			(hide yes)
			(effects
				(font
					(size 1 1)
					(thickness 0.15)
				)
				(justify mirror)
			)
		)
		(property "MPN" "GRM155R61H104KE14D"
			(at 0 0 0)
			(layer "B.Fab")
			(hide yes)
			(effects
				(font
					(size 1 1)
					(thickness 0.15)
				)
				(justify mirror)
			)
		)
		(property "Manufacturer" "Murata"
			(at 0 0 0)
			(layer "B.Fab")
			(hide yes)
			(effects
				(font
					(size 1 1)
					(thickness 0.15)
				)
				(justify mirror)
			)
		)
		(property "Public" ""
			(at 0 0 0)
			(layer "B.Fab")
			(hide yes)
			(effects
				(font
					(size 1 1)
					(thickness 0.15)
				)
				(justify mirror)
			)
		)
		(property "Val" "100n"
			(at 0 0 0)
			(layer "B.Fab")
			(hide yes)
			(effects
				(font
					(size 1 1)
					(thickness 0.15)
				)
				(justify mirror)
			)
		)
		(property "Voltage" "50V"
			(at 0 0 0)
			(layer "B.Fab")
			(hide yes)
			(effects
				(font
					(size 1 1)
					(thickness 0.15)
				)
				(justify mirror)
			)
		)
		(sheetname "/Ethernet/")
		(sheetfile "ethernet.kicad_sch")
		(attr smd)
		(fp_rect
			(start -0.925 0.47)
			(end 0.925 -0.47)
			(stroke
				(width 0.05)
				(type default)
			)
			(fill no)
			(layer "B.CrtYd")
		)
		(fp_line
			(start -0.494 -0.248)
			(end -0.494 0.25)
			(stroke
				(width 0.15)
				(type solid)
			)
			(layer "B.Fab")
		)
		(fp_line
			(start -0.494 0.25)
			(end 0.504 0.25)
			(stroke
				(width 0.15)
				(type solid)
			)
			(layer "B.Fab")
		)
		(fp_line
			(start 0.504 -0.248)
			(end -0.494 -0.248)
			(stroke
				(width 0.15)
				(type solid)
			)
			(layer "B.Fab")
		)
		(fp_line
			(start 0.504 0.25)
			(end 0.504 -0.248)
			(stroke
				(width 0.15)
				(type solid)
			)
			(layer "B.Fab")
		)
		(fp_text user "${REFERENCE}"
			(at -0.939 -4.599 180)
			(layer "B.Fab")
			(effects
				(font
					(size 0.7 0.7)
					(thickness 0.15)
				)
				(justify left bottom mirror)
			)
		)
		(fp_text user "Author: Antmicro"
			(at -0.939 -3.399 180)
			(layer "B.Fab")
			(effects
				(font
					(size 0.7 0.7)
					(thickness 0.15)
				)
				(justify left bottom mirror)
			)
		)
		(fp_text user "License: Apache-2.0"
			(at -0.939 -5.799 180)
			(layer "B.Fab")
			(effects
				(font
					(size 0.7 0.7)
					(thickness 0.15)
				)
				(justify left bottom mirror)
			)
		)
		(pad "1" smd roundrect
			(at -0.48 0)
			(size 0.59 0.64)
			(layers "B.Cu" "B.Mask" "B.Paste")
			(roundrect_rratio 0.25)
			(net 68 "/Ethernet/SGMII.TX0_N")
			(pintype "passive")
		)
		(pad "2" smd roundrect
			(at 0.48 0)
			(size 0.59 0.64)
			(layers "B.Cu" "B.Mask" "B.Paste")
			(roundrect_rratio 0.25)
			(net 167 "/Ethernet/SGMII_SI_N")
			(pintype "passive")
		)
	)
	(footprint "antmicro-footprints:R_0402_1005Metric"
		(layer "B.Cu")
		(at 225.6 142.345 180)
		(descr "Resistor SMD 0402")
		(tags "resistor SMD 0402")
		(property "Reference" "R143"
			(at -3.84 -0.375 0)
			(layer "B.SilkS")
			(effects
				(font
					(size 0.7 0.7)
					(thickness 0.15)
				)
				(justify left bottom mirror)
			)
		)
		(property "Value" "R_10k_0402"
			(at -1.011843 -1.772047 0)
			(layer "B.Fab")
			(hide yes)
			(effects
				(font
					(size 0.7 0.7)
					(thickness 0.15)
				)
				(justify left bottom mirror)
			)
		)
		(property "Datasheet" "https://www.bourns.com/docs/product-datasheets/cr.pdf"
			(at 0 0 180)
			(layer "F.Fab")
			(hide yes)
			(effects
				(font
					(size 1.27 1.27)
					(thickness 0.15)
				)
			)
		)
		(property "Description" "SMD Chip Resistor, 10 kohm, ± 1%, 62.5 mW, 0402 [1005 Metric], Thick Film, General Purpose"
			(at 0 0 180)
			(layer "F.Fab")
			(hide yes)
			(effects
				(font
					(size 1.27 1.27)
					(thickness 0.15)
				)
			)
		)
		(property "Author" "Antmicro"
			(at 451.2 284.69 0)
			(layer "B.Fab")
			(hide yes)
			(effects
				(font
					(size 1 1)
					(thickness 0.15)
				)
				(justify mirror)
			)
		)
		(property "License" "Apache-2.0"
			(at 451.2 284.69 0)
			(layer "B.Fab")
			(hide yes)
			(effects
				(font
					(size 1 1)
					(thickness 0.15)
				)
				(justify mirror)
			)
		)
		(property "MPN" "CR0402-FX-1002GLF"
			(at 451.2 284.69 0)
			(layer "B.Fab")
			(hide yes)
			(effects
				(font
					(size 1 1)
					(thickness 0.15)
				)
				(justify mirror)
			)
		)
		(property "Manufacturer" "Bourns"
			(at 451.2 284.69 0)
			(layer "B.Fab")
			(hide yes)
			(effects
				(font
					(size 1 1)
					(thickness 0.15)
				)
				(justify mirror)
			)
		)
		(property "Public" ""
			(at 451.2 284.69 0)
			(layer "B.Fab")
			(hide yes)
			(effects
				(font
					(size 1 1)
					(thickness 0.15)
				)
				(justify mirror)
			)
		)
		(property "Tolerance" "1%"
			(at 451.2 284.69 0)
			(layer "B.Fab")
			(hide yes)
			(effects
				(font
					(size 1 1)
					(thickness 0.15)
				)
				(justify mirror)
			)
		)
		(property "Val" "10k"
			(at 451.2 284.69 0)
			(layer "B.Fab")
			(hide yes)
			(effects
				(font
					(size 1 1)
					(thickness 0.15)
				)
				(justify mirror)
			)
		)
		(sheetname "/WiFi_Bluetooth/")
		(sheetfile "wifi_bt.kicad_sch")
		(attr smd)
		(fp_rect
			(start -0.925 0.47)
			(end 0.925 -0.47)
			(stroke
				(width 0.05)
				(type default)
			)
			(fill no)
			(layer "B.CrtYd")
		)
		(fp_rect
			(start -0.5 0.25)
			(end 0.5 -0.25)
			(stroke
				(width 0.15)
				(type solid)
			)
			(fill no)
			(layer "B.Fab")
		)
		(fp_text user "${REFERENCE}"
			(at -0.95 -3.168 0)
			(layer "B.Fab")
			(effects
				(font
					(size 0.7 0.7)
					(thickness 0.15)
				)
				(justify left bottom mirror)
			)
		)
		(fp_text user "Author: Antmicro"
			(at -0.95 -4.169 0)
			(layer "B.Fab")
			(effects
				(font
					(size 0.7 0.7)
					(thickness 0.15)
				)
				(justify left bottom mirror)
			)
		)
		(fp_text user "License: Apache-2.0"
			(at -0.95 -5.169 0)
			(layer "B.Fab")
			(effects
				(font
					(size 0.7 0.7)
					(thickness 0.15)
				)
				(justify left bottom mirror)
			)
		)
		(pad "1" smd roundrect
			(at -0.48 0 180)
			(size 0.59 0.64)
			(layers "B.Cu" "B.Mask" "B.Paste")
			(roundrect_rratio 0.25)
			(net 417 "GND")
			(pintype "passive")
		)
		(pad "2" smd roundrect
			(at 0.48 0 180)
			(size 0.59 0.64)
			(layers "B.Cu" "B.Mask" "B.Paste")
			(roundrect_rratio 0.25)
			(net 421 "/WiFi_Bluetooth/STRAP_0")
			(pintype "passive")
		)
	)
	(footprint "antmicro-footprints:Fiducial_1mm_Mask2mm"
		(layer "B.Cu")
		(at 224.7 117.1 180)
		(descr "Circular Fiducial, 1mm bare copper, 3mm soldermask opening")
		(tags "fiducial")
		(property "Reference" "FD4"
			(at 0 1.4 0)
			(layer "B.SilkS")
			(hide yes)
			(effects
				(font
					(size 0.7 0.7)
					(thickness 0.15)
				)
				(justify left bottom mirror)
			)
		)
		(property "Value" "Fiducial_1mm_Mask2mm"
			(at 0 -2.2 0)
			(layer "B.Fab")
			(hide yes)
			(effects
				(font
					(size 0.7 0.7)
					(thickness 0.15)
				)
				(justify left bottom mirror)
			)
		)
		(property "Description" "Fiducial mask "
			(at 0 0 180)
			(layer "F.Fab")
			(hide yes)
			(effects
				(font
					(size 1.27 1.27)
					(thickness 0.15)
				)
			)
		)
		(property "Author" "Antmicro"
			(at 449.4 234.2 0)
			(layer "B.Fab")
			(hide yes)
			(effects
				(font
					(size 1 1)
					(thickness 0.15)
				)
				(justify mirror)
			)
		)
		(property "License" "Apache-2.0"
			(at 449.4 234.2 0)
			(layer "B.Fab")
			(hide yes)
			(effects
				(font
					(size 1 1)
					(thickness 0.15)
				)
				(justify mirror)
			)
		)
		(property "exclude_from_bom" ""
			(at 449.4 234.2 0)
			(layer "B.Fab")
			(hide yes)
			(effects
				(font
					(size 1 1)
					(thickness 0.15)
				)
				(justify mirror)
			)
		)
		(sheetfile "polarfire-som.kicad_sch")
		(attr board_only exclude_from_pos_files exclude_from_bom)
		(fp_circle
			(center 0 0)
			(end 1.24 0)
			(stroke
				(width 0.05)
				(type solid)
			)
			(fill no)
			(layer "B.CrtYd")
		)
		(fp_circle
			(center 0 0)
			(end 0.999 0)
			(stroke
				(width 0.15)
				(type solid)
			)
			(fill no)
			(layer "B.Fab")
		)
		(fp_text user "${REFERENCE}"
			(at -1.25 -4.603 0)
			(layer "B.Fab")
			(effects
				(font
					(size 0.7 0.7)
					(thickness 0.15)
				)
				(justify left bottom mirror)
			)
		)
		(fp_text user "Author: Antmicro"
			(at -1.25 -5.803 0)
			(layer "B.Fab")
			(effects
				(font
					(size 0.7 0.7)
					(thickness 0.15)
				)
				(justify left bottom mirror)
			)
		)
		(fp_text user "License: Apache-2.0"
			(at -1.25 -7.003 0)
			(layer "B.Fab")
			(effects
				(font
					(size 0.7 0.7)
					(thickness 0.15)
				)
				(justify left bottom mirror)
			)
		)
		(pad "" smd circle
			(at 0 0 180)
			(size 1 1)
			(layers "B.Cu" "B.Mask")
			(solder_mask_margin 0.5)
			(clearance 0.5)
		)
	)
)
